FILE_TYPE = CONNECTIVITY;
{Allegro Design Entry HDL 17.4-2019 S026 (4007227) 1/17/2022}
"PAGE_NUMBER" = 76;
0"NC";
1"GND\g";
2"GND\g";
3"GND\g";
4"GND\g";
5"GND\g";
6"GND\g";
7"SPI_CPU0_LVC3_CS0_N";
8"SPI_CPU0_LVC3_CS1_N";
9"SPI_CPU0_LVC3_SCM_CS0_N";
10"SPI_CPU0_LVC3_CLK";
11"SPI_CPU0_LVC3_R_TPM_CS_N";
12"SPI_CPU0_LVC3_TPM_CS_N";
13"SPI_CPU0_LVC3_SCM_CS1_N";
14"SPI_CPU0_LVC3_SCM_CLK";
15"PVDD18_S5_P0\g";
16"PVDD18_S5_P0\g";
17"P3V3_AUX\g";
18"PVDD18_S5_P0\g";
19"P3V3_AUX\g";
20"PVDD18_S5_P0\g";
21"P3V3_AUX\g";
22"SPI_CPU0_D0";
23"SPI_CPU0_D2";
24"SPI_CPU0_D3";
25"SPI_CPU0_D1";
26"ROM_LS_EN";
27"SPI_CPU0_R1_D3";
28"SPI_CPU0_R1_D1";
29"SPI_CPU0_R1_D0";
30"SPI_CPU0_R1_D2";
31"ROM_SD_LS_OE";
32"SPI_CPU0_D3";
33"SPI_CPU0_LVC3_SCM_CLK";
34"SPI_CPU0_TPM_CS_N";
35"SPI_CPU0_CS0_N";
36"SPI_CPU0_CLK";
37"SPI_CPU0_LVC3_SCM_D1";
38"SPI_CPU0_LVC3_SCM_D0";
39"SPI_CPU0_CS1_N";
40"SPI_CPU0_LVC3_TPM_CS_N";
41"SPI_CPU0_LVC3_SCM_D3";
42"SPI_CPU0_LVC3_SCM_D2";
43"SPI_CPU0_LVC3_SCM_D2";
44"SPI_CPU0_LVC3_SCM_D3";
45"SPI_CPU0_LVC3_SCM_CS0_N";
46"SPI_CPU0_LVC3_SCM_D0";
47"SPI_CPU0_LVC3_SCM_D1";
48"SPI_CPU0_LVC3_SCM_CS1_N";
49"SPI_CPU0_CS0_N";
50"SPI_CPU0_TPM_CS_N";
51"SPI_CPU0_CS1_N";
52"SPI_CPU0_D0";
53"SPI_CPU0_D1";
54"SPI_CPU0_D2";
55"ROM_LS_EN";
56"SPI_CPU0_LVC3_D1";
57"SPI_CPU0_LVC3_D0";
58"SPI_CPU0_LVC3_D2";
59"SPI_CPU0_LVC3_D3";
%"UNIVERSAL_POWER"
"1","(-8025,6075)","0","pure_quanta_power","I105";
;
HDL_POWER"PVDD18_S5_P0"
CDS_LIB"pure_quanta_power";
"A"15;
%"Q_RES"
"2","(-8025,5875)","0","pure_quanta","I106";
;
LOCATION"R811"
$SEC"1"
CDS_SEC"1"
TOLERANCE"1%"
MATERIAL"CHIP"
WATTAGE"1/16W"
VALUE"1K"
CDS_LIB"pure_quanta"
PACK_TYPE"0402LF"
PART_NUMBER"CS21002FB06";
"A"
$PN"1"15;
"B"
$PN"2"49;
%"Q_RES"
"2","(-8200,5875)","0","pure_quanta","I107";
;
LOCATION"R659"
$SEC"1"
CDS_SEC"1"
TOLERANCE"1%"
WATTAGE"1/16W"
MATERIAL"CHIP"
VALUE"1K"
CDS_LIB"pure_quanta"
PACK_TYPE"0402LF"
PART_NUMBER"CS21002FB06";
"A"
$PN"1"15;
"B"
$PN"2"50;
%"Q_RES"
"2","(-8375,5875)","0","pure_quanta","I108";
;
LOCATION"R601"
$SEC"1"
CDS_SEC"1"
TOLERANCE"1%"
MATERIAL"CHIP"
WATTAGE"1/16W"
VALUE"1K"
CDS_LIB"pure_quanta"
PACK_TYPE"0402LF"
PART_NUMBER"CS21002FB06";
"A"
$PN"1"15;
"B"
$PN"2"51;
%"Q_RES"
"2","(-2225,5625)","2","pure_quanta","I115";
;
LOCATION"R20"
$SEC"1"
CDS_SEC"1"
MATERIAL"CHIP"
TOLERANCE"1%"
VALUE"10K"
CDS_LIB"pure_quanta"
WATTAGE"1/16W"
PACK_TYPE"0402LF"
PART_NUMBER"CS31002FB08";
"A"
$PN"1"21;
"B"
$PN"2"33;
%"Q_RES"
"2","(-1875,5625)","2","pure_quanta","I116";
;
LOCATION"R21"
$SEC"1"
CDS_SEC"1"
TOLERANCE"1%"
VALUE"1K"
MATERIAL"EMPTY"
PACK_TYPE"0402LF"
WATTAGE"1/16W"
CDS_LIB"pure_quanta"
PART_NUMBER"CS21002FB06";
"A"
$PN"1"21;
"B"
$PN"2"46;
%"Q_RES"
"2","(-1700,5625)","2","pure_quanta","I117";
;
LOCATION"R127"
$SEC"1"
CDS_SEC"1"
TOLERANCE"1%"
VALUE"1K"
MATERIAL"EMPTY"
PACK_TYPE"0402LF"
WATTAGE"1/16W"
CDS_LIB"pure_quanta"
PART_NUMBER"CS21002FB06";
"A"
$PN"1"21;
"B"
$PN"2"47;
%"Q_RES"
"2","(-1525,5625)","2","pure_quanta","I118";
;
LOCATION"R128"
$SEC"1"
CDS_SEC"1"
TOLERANCE"1%"
VALUE"1K"
MATERIAL"EMPTY"
PACK_TYPE"0402LF"
WATTAGE"1/16W"
CDS_LIB"pure_quanta"
PART_NUMBER"CS21002FB06";
"A"
$PN"1"21;
"B"
$PN"2"43;
%"Q_RES"
"2","(-1350,5625)","2","pure_quanta","I119";
;
LOCATION"R129"
$SEC"1"
CDS_SEC"1"
TOLERANCE"1%"
VALUE"1K"
MATERIAL"EMPTY"
WATTAGE"1/16W"
PACK_TYPE"0402LF"
CDS_LIB"pure_quanta"
PART_NUMBER"CS21002FB06";
"A"
$PN"1"21;
"B"
$PN"2"44;
%"Q_RES"
"2","(-8550,5875)","0","pure_quanta","I131";
;
LOCATION"R1532"
$SEC"1"
CDS_SEC"1"
TOLERANCE"1%"
WATTAGE"1/16W"
VALUE"1K"
MATERIAL"EMPTY"
CDS_LIB"pure_quanta"
PACK_TYPE"0402LF"
PART_NUMBER"CS21002FB06";
"A"
$PN"1"15;
"B"
$PN"2"52;
%"Q_RES"
"2","(-8725,5875)","0","pure_quanta","I132";
;
LOCATION"R1531"
$SEC"1"
CDS_SEC"1"
TOLERANCE"1%"
VALUE"1K"
MATERIAL"EMPTY"
WATTAGE"1/16W"
CDS_LIB"pure_quanta"
PACK_TYPE"0402LF"
PART_NUMBER"CS21002FB06";
"A"
$PN"1"15;
"B"
$PN"2"53;
%"Q_RES"
"2","(-8900,5875)","0","pure_quanta","I133";
;
LOCATION"R1530"
$SEC"1"
CDS_SEC"1"
TOLERANCE"1%"
VALUE"1K"
WATTAGE"1/16W"
MATERIAL"EMPTY"
CDS_LIB"pure_quanta"
PACK_TYPE"0402LF"
PART_NUMBER"CS21002FB06";
"A"
$PN"1"15;
"B"
$PN"2"54;
%"Q_RES"
"2","(-9075,5875)","0","pure_quanta","I134";
;
LOCATION"R1529"
$SEC"1"
CDS_SEC"1"
TOLERANCE"1%"
WATTAGE"1/16W"
MATERIAL"EMPTY"
VALUE"1K"
CDS_LIB"pure_quanta"
PACK_TYPE"0402LF"
PART_NUMBER"CS21002FB06";
"A"
$PN"1"15;
"B"
$PN"2"32;
%"UNIVERSAL_GND"
"1","(-6200,2500)","0","pure_quanta_power","I138";
;
CDS_LIB"pure_quanta_power"
HDL_POWER"GND";
"A"1;
%"UNIVERSAL_GND"
"1","(-4725,2450)","2","pure_quanta_power","I139";
;
CDS_LIB"pure_quanta_power"
HDL_POWER"GND";
"A"2;
%"Q_RES"
"2","(-1175,5625)","0","pure_quanta","I148";
;
LOCATION"R1547"
$SEC"1"
CDS_SEC"1"
MATERIAL"CHIP"
TOLERANCE"5%"
VALUE"4.7K"
PACK_TYPE"0402LF"
WATTAGE"1/16W"
CDS_LIB"pure_quanta"
PART_NUMBER"CS24702JB10";
"A"
$PN"1"21;
"B"
$PN"2"40;
%"Q_RES"
"2","(-9250,5875)","0","pure_quanta","I150";
;
LOCATION"R1567"
$SEC"1"
CDS_SEC"1"
MATERIAL"CHIP"
WATTAGE"1/16W"
TOLERANCE"5%"
VALUE"4.7K"
CDS_LIB"pure_quanta"
PACK_TYPE"0402LF"
PART_NUMBER"CS24702JB10";
"A"
$PN"1"15;
"B"
$PN"2"55;
%"Q_RES"
"1","(-3950,4225)","0","pure_quanta","I180";
;
LOCATION"R600"
$SEC"1"
CDS_SEC"1"
VALUE"0"
PACK_TYPE"0402LF"
TOLERANCE"5%"
MATERIAL"CHIP"
WATTAGE"1/16W"
CDS_LIB"pure_quanta"
PART_NUMBER"CS00002JB13";
"B"
$PN"2"13;
"A"
$PN"1"8;
%"Q_RES"
"2","(-1025,5625)","2","pure_quanta","I191";
;
LOCATION"R1655"
$SEC"1"
CDS_SEC"1"
TOLERANCE"1%"
MATERIAL"EMPTY"
VALUE"1K"
CDS_LIB"pure_quanta"
WATTAGE"1/16W"
PACK_TYPE"0402LF"
PART_NUMBER"CS21002FB06";
"A"
$PN"1"21;
"B"
$PN"2"48;
%"UNIVERSAL_POWER"
"1","(-6225,4100)","0","pure_quanta_power","I192";
;
HDL_POWER"PVDD18_S5_P0"
CDS_LIB"pure_quanta_power";
"A"16;
%"Q_RES"
"1","(-4075,2325)","0","pure_quanta","I205";
;
LOCATION"R606"
$SEC"1"
CDS_SEC"1"
VALUE"0"
PACK_TYPE"0402LF"
TOLERANCE"5%"
MATERIAL"CHIP"
WATTAGE"1/16W"
CDS_LIB"pure_quanta"
PART_NUMBER"CS00002JB13";
"B"
$PN"2"42;
"A"
$PN"1"58;
%"Q_RES"
"1","(-4075,2375)","0","pure_quanta","I207";
;
LOCATION"R607"
$SEC"1"
CDS_SEC"1"
VALUE"0"
WATTAGE"1/16W"
MATERIAL"CHIP"
TOLERANCE"5%"
PACK_TYPE"0402LF"
CDS_LIB"pure_quanta"
PART_NUMBER"CS00002JB13";
"B"
$PN"2"41;
"A"
$PN"1"59;
%"Q_RES"
"1","(-4075,2225)","0","pure_quanta","I219";
;
LOCATION"R605"
$SEC"1"
CDS_SEC"1"
VALUE"49.9"
TOLERANCE"1%"
CDS_LIB"pure_quanta"
WATTAGE"1/16W"
MATERIAL"CHIP"
PACK_TYPE"0402LF"
PART_NUMBER"CS04992FB07";
"B"
$PN"2"37;
"A"
$PN"1"56;
%"Q_RES"
"1","(-4075,2275)","0","pure_quanta","I221";
;
LOCATION"R604"
$SEC"1"
CDS_SEC"1"
VALUE"33.2"
TOLERANCE"1%"
CDS_LIB"pure_quanta"
WATTAGE"1/16W"
MATERIAL"CHIP"
PACK_TYPE"0402LF"
PART_NUMBER"CS03322FB03";
"B"
$PN"2"38;
"A"
$PN"1"57;
%"Q_RES"
"1","(-3950,4325)","0","pure_quanta","I228";
;
LOCATION"R603"
$SEC"1"
CDS_SEC"1"
VALUE"0"
CDS_LIB"pure_quanta"
WATTAGE"1/16W"
MATERIAL"CHIP"
TOLERANCE"5%"
PACK_TYPE"0402LF"
PART_NUMBER"CS00002JB13";
"B"
$PN"2"9;
"A"
$PN"1"7;
%"Q_RES"
"1","(-3950,4275)","0","pure_quanta","I230";
;
LOCATION"R602"
$SEC"1"
CDS_SEC"1"
VALUE"33"
WATTAGE"1/16W"
MATERIAL"CHIP"
TOLERANCE"5%"
PACK_TYPE"0402LF"
CDS_LIB"pure_quanta"
PART_NUMBER"CS03302JB10";
"B"
$PN"2"14;
"A"
$PN"1"10;
%"Q_RES"
"1","(-6800,2375)","0","pure_quanta","I234";
;
LOCATION"R8005"
SEC"1"
MATERIAL"CHIP"
VALUE"33"
PACK_TYPE"0402LF"
WATTAGE"1/16W"
TOLERANCE"5%"
SEC_TYPE"0402LF"
CDS_LIB"pure_quanta"
PART_NUMBER"CS03302JB10";
"B"
$PN"2"27;
"A"
$PN"1"24;
%"Q_RES"
"1","(-6800,2325)","0","pure_quanta","I239";
;
LOCATION"R8006"
SEC"1"
VALUE"33"
PACK_TYPE"0402LF"
SEC_TYPE"0402LF"
WATTAGE"1/16W"
MATERIAL"CHIP"
TOLERANCE"5%"
CDS_LIB"pure_quanta"
PART_NUMBER"CS03302JB10";
"B"
$PN"2"30;
"A"
$PN"1"23;
%"Q_RES"
"1","(-6800,2275)","0","pure_quanta","I240";
;
LOCATION"R8007"
SEC"1"
VALUE"33"
WATTAGE"1/16W"
MATERIAL"CHIP"
TOLERANCE"5%"
CDS_LIB"pure_quanta"
SEC_TYPE"0402LF"
PACK_TYPE"0402LF"
PART_NUMBER"CS03302JB10";
"B"
$PN"2"29;
"A"
$PN"1"22;
%"Q_RES"
"1","(-6800,2225)","0","pure_quanta","I241";
;
LOCATION"R8008"
SEC"1"
VALUE"33"
WATTAGE"1/16W"
MATERIAL"CHIP"
TOLERANCE"5%"
CDS_LIB"pure_quanta"
SEC_TYPE"0402LF"
PACK_TYPE"0402LF"
PART_NUMBER"CS03302JB10";
"B"
$PN"2"28;
"A"
$PN"1"25;
%"Q_RES"
"1","(-3950,4175)","0","pure_quanta","I242";
;
LOCATION"R608"
$SEC"1"
CDS_SEC"1"
VALUE"33"
CDS_LIB"pure_quanta"
WATTAGE"1/16W"
MATERIAL"CHIP"
TOLERANCE"5%"
PACK_TYPE"0402LF"
PART_NUMBER"CS03302JB10";
"B"
$PN"2"12;
"A"
$PN"1"11;
%"UNIVERSAL_POWER"
"1","(-4875,5000)","0","pure_quanta_power","I49";
;
HDL_POWER"P3V3_AUX"
CDS_LIB"pure_quanta_power";
"A"17;
%"Q_CAP"
"1","(-4750,4750)","0","pure_quanta","I50";
;
LOCATION"C1104"
$SEC"1"
CDS_SEC"1"
PACK_TYPE"0402"
VALUE"0.1UF"
MATERIAL"X7R"
VOLTAGE"25V"
TOLERANCE"10%"
CDS_LIB"pure_quanta"
PART_NUMBER"CH4104K1B00";
"B"
$PN"2"3;
"A"
$PN"1"17;
%"UNIVERSAL_GND"
"1","(-4750,4550)","2","pure_quanta_power","I51";
;
CDS_LIB"pure_quanta_power"
HDL_POWER"GND";
"A"3;
%"UNIVERSAL_POWER"
"1","(-5975,4975)","0","pure_quanta_power","I52";
;
HDL_POWER"PVDD18_S5_P0"
CDS_LIB"pure_quanta_power";
"A"18;
%"Q_CAP"
"1","(-6100,4750)","2","pure_quanta","I53";
;
LOCATION"C1102"
$SEC"1"
CDS_SEC"1"
TOLERANCE"10%"
VOLTAGE"25V"
VALUE"0.1UF"
MATERIAL"X7R"
PACK_TYPE"0402"
CDS_LIB"pure_quanta"
PART_NUMBER"CH4104K1B00";
"B"
$PN"2"4;
"A"
$PN"1"18;
%"UNIVERSAL_GND"
"1","(-6100,4550)","0","pure_quanta_power","I54";
;
CDS_LIB"pure_quanta_power"
HDL_POWER"GND";
"A"4;
%"UNIVERSAL_GND"
"1","(-4775,3550)","2","pure_quanta_power","I56";
;
CDS_LIB"pure_quanta_power"
HDL_POWER"GND";
"A"5;
%"UNIVERSAL_POWER"
"1","(-4850,2900)","0","pure_quanta_power","I57";
;
HDL_POWER"P3V3_AUX"
CDS_LIB"pure_quanta_power";
"A"19;
%"Q_CAP"
"1","(-4725,2650)","0","pure_quanta","I59";
;
LOCATION"C1105"
$SEC"1"
CDS_SEC"1"
VOLTAGE"25V"
TOLERANCE"10%"
VALUE"0.1UF"
MATERIAL"X7R"
PACK_TYPE"0402"
CDS_LIB"pure_quanta"
PART_NUMBER"CH4104K1B00";
"B"
$PN"2"2;
"A"
$PN"1"19;
%"UNIVERSAL_GND"
"1","(-4825,1700)","2","pure_quanta_power","I62";
;
CDS_LIB"pure_quanta_power"
HDL_POWER"GND";
"A"6;
%"SN74AVC4T774PWR"
"1","(-5425,4175)","0","pure_quanta","I63";
;
LOCATION"U53"
$SEC"1"
CDS_SEC"1"
VALUE"SN74AVC4T774PWR"
MATERIAL"IC"
PART_TYPE"SMLF"
CDS_LMAN_SYM_OUTLINE"-250,450,250,-450"
NEEDS_NO_SIZE"TRUE"
CDS_LIB"pure_quanta"
PART_NUMBER"AL04T774K00";
"VCCA"
$PN"16"18;
"VCCB"
$PN"15"17;
"B1"
$PN"14"7;
"B2"
$PN"13"10;
"B3"
$PN"12"8;
"B4"
$PN"11"11;
"GND"
$PN"10"5;
"OE \B"
$PN"9"31;
"DIR4"
$PN"8"16;
"DIR3"
$PN"7"16;
"A4"
$PN"6"34;
"A3"
$PN"5"39;
"A2"
$PN"4"36;
"A1"
$PN"3"35;
"DIR2"
$PN"2"16;
"DIR1"
$PN"1"16;
%"UNIVERSAL_POWER"
"1","(-6075,2900)","0","pure_quanta_power","I64";
;
HDL_POWER"PVDD18_S5_P0"
CDS_LIB"pure_quanta_power";
"A"20;
%"Q_CAP"
"1","(-6200,2675)","2","pure_quanta","I65";
;
LOCATION"C1103"
$SEC"1"
CDS_SEC"1"
PACK_TYPE"0402"
VALUE"0.1UF"
MATERIAL"X7R"
TOLERANCE"10%"
VOLTAGE"25V"
CDS_LIB"pure_quanta"
PART_NUMBER"CH4104K1B00";
"B"
$PN"2"1;
"A"
$PN"1"20;
%"PI4ULS3V304AZMAEX"
"1","(-5550,2275)","0","pure_quanta","I67";
;
LOCATION"U54"
$SEC"1"
CDS_SEC"1"
PART_TYPE"SMLF"
MATERIAL"IC"
VALUE"PI4ULS3V304AZMAEX"
CDS_LMAN_SYM_OUTLINE"-250,250,250,-250"
NEEDS_NO_SIZE"TRUE"
CDS_LIB"pure_quanta"
PART_NUMBER"AL000304005";
"GND"
$PN"6"6;
"B4"
$PN"7"56;
"B3"
$PN"8"57;
"B2"
$PN"9"58;
"B1"
$PN"10"59;
"VCCA"
$PN"1"20;
"A4"
$PN"5"28;
"EN"
$PN"12"26;
"VCCB"
$PN"11"19;
"A3"
$PN"4"29;
"A2"
$PN"3"30;
"A1"
$PN"2"27;
%"UNIVERSAL_POWER"
"1","(-2225,5925)","2","pure_quanta_power","I96";
;
HDL_POWER"P3V3_AUX"
CDS_LIB"pure_quanta_power";
"A"21;
%"Q_RES"
"2","(-2050,5625)","2","pure_quanta","I97";
;
LOCATION"R610"
$SEC"1"
CDS_SEC"1"
TOLERANCE"1%"
VALUE"1K"
MATERIAL"EMPTY"
CDS_LIB"pure_quanta"
WATTAGE"1/16W"
PACK_TYPE"0402LF"
PART_NUMBER"CS21002FB06";
"A"
$PN"1"21;
"B"
$PN"2"45;
END.
